(kicad_pcb
	(version 20260206)
	(generator "pcbnew")
	(generator_version "10.0")
	(general
		(thickness 1.6)
		(legacy_teardrops no)
	)
	(paper "A4")
	(title_block
		(title "03242023_DA0F0TMBIJ0_F0T_Motherboard_J_brd_V01_OCP.brd")
		(comment 1 "Grand Teton / footprints 4046-4052 of 6105")
	)
	(layers
		(0 "F.Cu" signal "TOP")
		(4 "In1.Cu" signal "GND")
		(6 "In2.Cu" signal "IN1")
		(8 "In3.Cu" signal "GND1")
		(10 "In4.Cu" signal "IN2")
		(12 "In5.Cu" signal "GND2")
		(14 "In6.Cu" signal "IN3")
		(16 "In7.Cu" signal "GND3")
		(18 "In8.Cu" signal "VCC")
		(20 "In9.Cu" signal "VCC1")
		(22 "In10.Cu" signal "GND4")
		(24 "In11.Cu" signal "IN4")
		(26 "In12.Cu" signal "GND5")
		(28 "In13.Cu" signal "IN5")
		(30 "In14.Cu" signal "GND6")
		(32 "In15.Cu" signal "IN6")
		(34 "In16.Cu" signal "GND7")
		(2 "B.Cu" signal "BOTTOM")
		(9 "F.Adhes" user "F.Adhesive")
		(11 "B.Adhes" user "B.Adhesive")
		(13 "F.Paste" user "Package Geometry/Pastemask Top")
		(15 "B.Paste" user "Package Geometry/Pastemask Bottom")
		(5 "F.SilkS" user "Ref Des/Silkscreen Top")
		(7 "B.SilkS" user "Ref Des/Silkscreen Bottom")
		(1 "F.Mask" user "Board Geometry/Soldermask Top")
		(3 "B.Mask" user "Board Geometry/Soldermask Bottom")
		(17 "Dwgs.User" user "User.Drawings")
		(19 "Cmts.User" user "User.Comments")
		(21 "Eco1.User" user "User.Eco1")
		(23 "Eco2.User" user "User.Eco2")
		(25 "Edge.Cuts" user "Board Geometry/Outline")
		(27 "Margin" user)
		(31 "F.CrtYd" user "Package Geometry/Place Bound Top")
		(29 "B.CrtYd" user "Package Geometry/Place Bound Bottom")
		(35 "F.Fab" user "Ref Des/Assembly Top")
		(33 "B.Fab" user "Ref Des/Assembly Bottom")
	)
	(footprint ""
		(layer "F.Cu")
		(at 15.436596 -390.167876)
		(property "Reference" "R3289"
			(at 0 0 0)
			(layer "F.SilkS")
			(hide yes)
			(effects
				(font
					(size 1.27 1.27)
				)
			)
		)
		(property "Value" ""
			(at 0 0 0)
			(layer "F.Fab")
			(effects
				(font
					(size 1.27 1.27)
				)
			)
		)
		(duplicate_pad_numbers_are_jumpers no)
		(fp_line
			(start -0.7874 -0.4064)
			(end 0.7874 -0.4064)
			(stroke
				(width 0.1524)
				(type default)
			)
			(layer "F.SilkS")
		)
		(fp_line
			(start -0.7874 0.4064)
			(end -0.7874 -0.4064)
			(stroke
				(width 0.1524)
				(type default)
			)
			(layer "F.SilkS")
		)
		(fp_line
			(start 0.7874 -0.4064)
			(end 0.7874 0.4064)
			(stroke
				(width 0.1524)
				(type default)
			)
			(layer "F.SilkS")
		)
		(fp_line
			(start 0.7874 0.4064)
			(end -0.7874 0.4064)
			(stroke
				(width 0.1524)
				(type default)
			)
			(layer "F.SilkS")
		)
		(fp_line
			(start -0.67945 -0.305054)
			(end -0.12065 -0.305054)
			(stroke
				(width 0.1)
				(type default)
			)
			(layer "F.Fab")
		)
		(fp_line
			(start -0.67945 0.3048)
			(end -0.67945 -0.305054)
			(stroke
				(width 0.1)
				(type default)
			)
			(layer "F.Fab")
		)
		(fp_line
			(start -0.12065 -0.305054)
			(end -0.12065 -0.2794)
			(stroke
				(width 0.1)
				(type default)
			)
			(layer "F.Fab")
		)
		(fp_line
			(start -0.12065 -0.2794)
			(end 0.12065 -0.2794)
			(stroke
				(width 0.1)
				(type default)
			)
			(layer "F.Fab")
		)
		(fp_line
			(start -0.12065 0.2794)
			(end -0.12065 0.3048)
			(stroke
				(width 0.1)
				(type default)
			)
			(layer "F.Fab")
		)
		(fp_line
			(start -0.12065 0.3048)
			(end -0.67945 0.3048)
			(stroke
				(width 0.1)
				(type default)
			)
			(layer "F.Fab")
		)
		(fp_line
			(start 0.120396 0.2794)
			(end -0.12065 0.2794)
			(stroke
				(width 0.1)
				(type default)
			)
			(layer "F.Fab")
		)
		(fp_line
			(start 0.120396 0.3048)
			(end 0.120396 0.2794)
			(stroke
				(width 0.1)
				(type default)
			)
			(layer "F.Fab")
		)
		(fp_line
			(start 0.12065 -0.3048)
			(end 0.67945 -0.3048)
			(stroke
				(width 0.1)
				(type default)
			)
			(layer "F.Fab")
		)
		(fp_line
			(start 0.12065 -0.2794)
			(end 0.12065 -0.3048)
			(stroke
				(width 0.1)
				(type default)
			)
			(layer "F.Fab")
		)
		(fp_line
			(start 0.67945 -0.3048)
			(end 0.67945 0.3048)
			(stroke
				(width 0.1)
				(type default)
			)
			(layer "F.Fab")
		)
		(fp_line
			(start 0.67945 0.3048)
			(end 0.120396 0.3048)
			(stroke
				(width 0.1)
				(type default)
			)
			(layer "F.Fab")
		)
		(pad "1" smd circle
			(at -0.40005 0)
			(size 0 0)
			(layers "F.Cu" "F.Mask" "F.Paste")
			(net "P3V3_AUX")
		)
		(pad "2" smd circle
			(at 0.40005 0)
			(size 0 0)
			(layers "F.Cu" "F.Mask" "F.Paste")
			(net "FM_P2E_SWA")
		)
	)
	(footprint ""
		(layer "F.Cu")
		(at 381.360172 -297.514772)
		(property "Reference" "H17"
			(at -1.122172 -5.826506 0)
			(unlocked yes)
			(layer "F.SilkS")
			(effects
				(font
					(size 0.7874 0.5842)
					(thickness 0.1524)
				)
				(justify left)
			)
		)
		(property "Value" ""
			(at 0 0 0)
			(layer "F.Fab")
			(effects
				(font
					(size 1.27 1.27)
				)
			)
		)
		(duplicate_pad_numbers_are_jumpers no)
		(fp_circle
			(center 0 0)
			(end 2.5273 0)
			(stroke
				(width 0.1524)
				(type default)
			)
			(fill no)
			(layer "F.SilkS")
		)
		(fp_circle
			(center 0 0)
			(end 2.5273 0)
			(stroke
				(width 0.1524)
				(type default)
			)
			(fill no)
			(layer "B.SilkS")
		)
		(fp_circle
			(center 0 0)
			(end 2.5273 0)
			(stroke
				(width 0.1)
				(type default)
			)
			(fill no)
			(layer "B.Fab")
		)
		(fp_circle
			(center 0 0)
			(end 2.5273 0)
			(stroke
				(width 0.1)
				(type default)
			)
			(fill no)
			(layer "F.Fab")
		)
		(pad "" np_thru_hole circle
			(at 0 0)
			(size 3.429 3.429)
			(drill 3.429)
			(layers "*.Cu" "*.Mask")
			(clearance 0.381)
			(thermal_gap 0.381)
		)
	)
	(footprint ""
		(layer "F.Cu")
		(at 279.262078 -417.2839 -90)
		(property "Reference" "R4668"
			(at 0 0 270)
			(layer "F.SilkS")
			(hide yes)
			(effects
				(font
					(size 1.27 1.27)
				)
			)
		)
		(property "Value" ""
			(at 0 0 270)
			(layer "F.Fab")
			(effects
				(font
					(size 1.27 1.27)
				)
			)
		)
		(duplicate_pad_numbers_are_jumpers no)
		(fp_line
			(start -0.7874 0.4064)
			(end -0.7874 -0.4064)
			(stroke
				(width 0.1524)
				(type default)
			)
			(layer "F.SilkS")
		)
		(fp_line
			(start 0.7874 0.4064)
			(end -0.7874 0.4064)
			(stroke
				(width 0.1524)
				(type default)
			)
			(layer "F.SilkS")
		)
		(fp_line
			(start -0.7874 -0.4064)
			(end 0.7874 -0.4064)
			(stroke
				(width 0.1524)
				(type default)
			)
			(layer "F.SilkS")
		)
		(fp_line
			(start 0.7874 -0.4064)
			(end 0.7874 0.4064)
			(stroke
				(width 0.1524)
				(type default)
			)
			(layer "F.SilkS")
		)
		(fp_line
			(start -0.67945 0.3048)
			(end -0.67945 -0.305054)
			(stroke
				(width 0.1)
				(type default)
			)
			(layer "F.Fab")
		)
		(fp_line
			(start -0.12065 0.3048)
			(end -0.67945 0.3048)
			(stroke
				(width 0.1)
				(type default)
			)
			(layer "F.Fab")
		)
		(fp_line
			(start 0.120396 0.3048)
			(end 0.120396 0.2794)
			(stroke
				(width 0.1)
				(type default)
			)
			(layer "F.Fab")
		)
		(fp_line
			(start 0.67945 0.3048)
			(end 0.120396 0.3048)
			(stroke
				(width 0.1)
				(type default)
			)
			(layer "F.Fab")
		)
		(fp_line
			(start -0.12065 0.2794)
			(end -0.12065 0.3048)
			(stroke
				(width 0.1)
				(type default)
			)
			(layer "F.Fab")
		)
		(fp_line
			(start 0.120396 0.2794)
			(end -0.12065 0.2794)
			(stroke
				(width 0.1)
				(type default)
			)
			(layer "F.Fab")
		)
		(fp_line
			(start -0.12065 -0.2794)
			(end 0.12065 -0.2794)
			(stroke
				(width 0.1)
				(type default)
			)
			(layer "F.Fab")
		)
		(fp_line
			(start 0.12065 -0.2794)
			(end 0.12065 -0.3048)
			(stroke
				(width 0.1)
				(type default)
			)
			(layer "F.Fab")
		)
		(fp_line
			(start 0.12065 -0.3048)
			(end 0.67945 -0.3048)
			(stroke
				(width 0.1)
				(type default)
			)
			(layer "F.Fab")
		)
		(fp_line
			(start 0.67945 -0.3048)
			(end 0.67945 0.3048)
			(stroke
				(width 0.1)
				(type default)
			)
			(layer "F.Fab")
		)
		(fp_line
			(start -0.67945 -0.305054)
			(end -0.12065 -0.305054)
			(stroke
				(width 0.1)
				(type default)
			)
			(layer "F.Fab")
		)
		(fp_line
			(start -0.12065 -0.305054)
			(end -0.12065 -0.2794)
			(stroke
				(width 0.1)
				(type default)
			)
			(layer "F.Fab")
		)
		(pad "1" smd circle
			(at -0.40005 0 270)
			(size 0 0)
			(layers "F.Cu" "F.Mask" "F.Paste")
			(net "A_HSC_LOW")
		)
		(pad "2" smd circle
			(at 0.40005 0 270)
			(size 0 0)
			(layers "F.Cu" "F.Mask" "F.Paste")
			(net "GND")
		)
	)
	(footprint ""
		(layer "F.Cu")
		(at 211.572094 -14.892528)
		(property "Reference" "C1275"
			(at 0 0 0)
			(layer "F.SilkS")
			(hide yes)
			(effects
				(font
					(size 1.27 1.27)
				)
			)
		)
		(property "Value" ""
			(at 0 0 0)
			(layer "F.Fab")
			(effects
				(font
					(size 1.27 1.27)
				)
			)
		)
		(duplicate_pad_numbers_are_jumpers no)
		(fp_line
			(start -0.7874 -0.4064)
			(end 0.7874 -0.4064)
			(stroke
				(width 0.1524)
				(type default)
			)
			(layer "F.SilkS")
		)
		(fp_line
			(start -0.7874 0.4064)
			(end -0.7874 -0.4064)
			(stroke
				(width 0.1524)
				(type default)
			)
			(layer "F.SilkS")
		)
		(fp_line
			(start 0.7874 -0.4064)
			(end 0.7874 0.4064)
			(stroke
				(width 0.1524)
				(type default)
			)
			(layer "F.SilkS")
		)
		(fp_line
			(start 0.7874 0.4064)
			(end -0.7874 0.4064)
			(stroke
				(width 0.1524)
				(type default)
			)
			(layer "F.SilkS")
		)
		(fp_line
			(start -0.67945 -0.305054)
			(end -0.12065 -0.305054)
			(stroke
				(width 0.1)
				(type default)
			)
			(layer "F.Fab")
		)
		(fp_line
			(start -0.67945 0.3048)
			(end -0.67945 -0.305054)
			(stroke
				(width 0.1)
				(type default)
			)
			(layer "F.Fab")
		)
		(fp_line
			(start -0.12065 -0.305054)
			(end -0.12065 -0.2794)
			(stroke
				(width 0.1)
				(type default)
			)
			(layer "F.Fab")
		)
		(fp_line
			(start -0.12065 -0.2794)
			(end 0.12065 -0.2794)
			(stroke
				(width 0.1)
				(type default)
			)
			(layer "F.Fab")
		)
		(fp_line
			(start -0.12065 0.2794)
			(end -0.12065 0.3048)
			(stroke
				(width 0.1)
				(type default)
			)
			(layer "F.Fab")
		)
		(fp_line
			(start -0.12065 0.3048)
			(end -0.67945 0.3048)
			(stroke
				(width 0.1)
				(type default)
			)
			(layer "F.Fab")
		)
		(fp_line
			(start 0.120396 0.2794)
			(end -0.12065 0.2794)
			(stroke
				(width 0.1)
				(type default)
			)
			(layer "F.Fab")
		)
		(fp_line
			(start 0.120396 0.3048)
			(end 0.120396 0.2794)
			(stroke
				(width 0.1)
				(type default)
			)
			(layer "F.Fab")
		)
		(fp_line
			(start 0.12065 -0.3048)
			(end 0.67945 -0.3048)
			(stroke
				(width 0.1)
				(type default)
			)
			(layer "F.Fab")
		)
		(fp_line
			(start 0.12065 -0.2794)
			(end 0.12065 -0.3048)
			(stroke
				(width 0.1)
				(type default)
			)
			(layer "F.Fab")
		)
		(fp_line
			(start 0.67945 -0.3048)
			(end 0.67945 0.3048)
			(stroke
				(width 0.1)
				(type default)
			)
			(layer "F.Fab")
		)
		(fp_line
			(start 0.67945 0.3048)
			(end 0.120396 0.3048)
			(stroke
				(width 0.1)
				(type default)
			)
			(layer "F.Fab")
		)
		(pad "1" smd circle
			(at -0.40005 0)
			(size 0 0)
			(layers "F.Cu" "F.Mask" "F.Paste")
			(net "P3V3_AUX")
		)
		(pad "2" smd circle
			(at 0.40005 0)
			(size 0 0)
			(layers "F.Cu" "F.Mask" "F.Paste")
			(net "GND")
		)
	)
	(footprint ""
		(layer "F.Cu")
		(at 365.2012 -412.623 180)
		(property "Reference" "R4798"
			(at 0 0 180)
			(layer "F.SilkS")
			(hide yes)
			(effects
				(font
					(size 1.27 1.27)
				)
			)
		)
		(property "Value" ""
			(at 0 0 180)
			(layer "F.Fab")
			(effects
				(font
					(size 1.27 1.27)
				)
			)
		)
		(duplicate_pad_numbers_are_jumpers no)
		(fp_line
			(start 0.7874 0.4064)
			(end -0.7874 0.4064)
			(stroke
				(width 0.1524)
				(type default)
			)
			(layer "F.SilkS")
		)
		(fp_line
			(start 0.7874 -0.4064)
			(end 0.7874 0.4064)
			(stroke
				(width 0.1524)
				(type default)
			)
			(layer "F.SilkS")
		)
		(fp_line
			(start -0.7874 0.4064)
			(end -0.7874 -0.4064)
			(stroke
				(width 0.1524)
				(type default)
			)
			(layer "F.SilkS")
		)
		(fp_line
			(start -0.7874 -0.4064)
			(end 0.7874 -0.4064)
			(stroke
				(width 0.1524)
				(type default)
			)
			(layer "F.SilkS")
		)
		(fp_line
			(start 0.67945 0.3048)
			(end 0.120396 0.3048)
			(stroke
				(width 0.1)
				(type default)
			)
			(layer "F.Fab")
		)
		(fp_line
			(start 0.67945 -0.3048)
			(end 0.67945 0.3048)
			(stroke
				(width 0.1)
				(type default)
			)
			(layer "F.Fab")
		)
		(fp_line
			(start 0.12065 -0.2794)
			(end 0.12065 -0.3048)
			(stroke
				(width 0.1)
				(type default)
			)
			(layer "F.Fab")
		)
		(fp_line
			(start 0.12065 -0.3048)
			(end 0.67945 -0.3048)
			(stroke
				(width 0.1)
				(type default)
			)
			(layer "F.Fab")
		)
		(fp_line
			(start 0.120396 0.3048)
			(end 0.120396 0.2794)
			(stroke
				(width 0.1)
				(type default)
			)
			(layer "F.Fab")
		)
		(fp_line
			(start 0.120396 0.2794)
			(end -0.12065 0.2794)
			(stroke
				(width 0.1)
				(type default)
			)
			(layer "F.Fab")
		)
		(fp_line
			(start -0.12065 0.3048)
			(end -0.67945 0.3048)
			(stroke
				(width 0.1)
				(type default)
			)
			(layer "F.Fab")
		)
		(fp_line
			(start -0.12065 0.2794)
			(end -0.12065 0.3048)
			(stroke
				(width 0.1)
				(type default)
			)
			(layer "F.Fab")
		)
		(fp_line
			(start -0.12065 -0.2794)
			(end 0.12065 -0.2794)
			(stroke
				(width 0.1)
				(type default)
			)
			(layer "F.Fab")
		)
		(fp_line
			(start -0.12065 -0.305054)
			(end -0.12065 -0.2794)
			(stroke
				(width 0.1)
				(type default)
			)
			(layer "F.Fab")
		)
		(fp_line
			(start -0.67945 0.3048)
			(end -0.67945 -0.305054)
			(stroke
				(width 0.1)
				(type default)
			)
			(layer "F.Fab")
		)
		(fp_line
			(start -0.67945 -0.305054)
			(end -0.12065 -0.305054)
			(stroke
				(width 0.1)
				(type default)
			)
			(layer "F.Fab")
		)
		(pad "1" smd circle
			(at -0.40005 0 180)
			(size 0 0)
			(layers "F.Cu" "F.Mask" "F.Paste")
			(net "P3V3_AUX")
		)
		(pad "2" smd circle
			(at 0.40005 0 180)
			(size 0 0)
			(layers "F.Cu" "F.Mask" "F.Paste")
			(net "PRSNT_CABLE_GPU_A3_N")
		)
	)
	(footprint ""
		(layer "F.Cu")
		(at 176.059338 -415.713418 180)
		(property "Reference" "R3465"
			(at 0 0 180)
			(layer "F.SilkS")
			(hide yes)
			(effects
				(font
					(size 1.27 1.27)
				)
			)
		)
		(property "Value" ""
			(at 0 0 180)
			(layer "F.Fab")
			(effects
				(font
					(size 1.27 1.27)
				)
			)
		)
		(duplicate_pad_numbers_are_jumpers no)
		(fp_line
			(start 0.7874 0.4064)
			(end -0.7874 0.4064)
			(stroke
				(width 0.1524)
				(type default)
			)
			(layer "F.SilkS")
		)
		(fp_line
			(start 0.7874 -0.4064)
			(end 0.7874 0.4064)
			(stroke
				(width 0.1524)
				(type default)
			)
			(layer "F.SilkS")
		)
		(fp_line
			(start -0.7874 0.4064)
			(end -0.7874 -0.4064)
			(stroke
				(width 0.1524)
				(type default)
			)
			(layer "F.SilkS")
		)
		(fp_line
			(start -0.7874 -0.4064)
			(end 0.7874 -0.4064)
			(stroke
				(width 0.1524)
				(type default)
			)
			(layer "F.SilkS")
		)
		(fp_line
			(start 0.67945 0.3048)
			(end 0.120396 0.3048)
			(stroke
				(width 0.1)
				(type default)
			)
			(layer "F.Fab")
		)
		(fp_line
			(start 0.67945 -0.3048)
			(end 0.67945 0.3048)
			(stroke
				(width 0.1)
				(type default)
			)
			(layer "F.Fab")
		)
		(fp_line
			(start 0.12065 -0.2794)
			(end 0.12065 -0.3048)
			(stroke
				(width 0.1)
				(type default)
			)
			(layer "F.Fab")
		)
		(fp_line
			(start 0.12065 -0.3048)
			(end 0.67945 -0.3048)
			(stroke
				(width 0.1)
				(type default)
			)
			(layer "F.Fab")
		)
		(fp_line
			(start 0.120396 0.3048)
			(end 0.120396 0.2794)
			(stroke
				(width 0.1)
				(type default)
			)
			(layer "F.Fab")
		)
		(fp_line
			(start 0.120396 0.2794)
			(end -0.12065 0.2794)
			(stroke
				(width 0.1)
				(type default)
			)
			(layer "F.Fab")
		)
		(fp_line
			(start -0.12065 0.3048)
			(end -0.67945 0.3048)
			(stroke
				(width 0.1)
				(type default)
			)
			(layer "F.Fab")
		)
		(fp_line
			(start -0.12065 0.2794)
			(end -0.12065 0.3048)
			(stroke
				(width 0.1)
				(type default)
			)
			(layer "F.Fab")
		)
		(fp_line
			(start -0.12065 -0.2794)
			(end 0.12065 -0.2794)
			(stroke
				(width 0.1)
				(type default)
			)
			(layer "F.Fab")
		)
		(fp_line
			(start -0.12065 -0.305054)
			(end -0.12065 -0.2794)
			(stroke
				(width 0.1)
				(type default)
			)
			(layer "F.Fab")
		)
		(fp_line
			(start -0.67945 0.3048)
			(end -0.67945 -0.305054)
			(stroke
				(width 0.1)
				(type default)
			)
			(layer "F.Fab")
		)
		(fp_line
			(start -0.67945 -0.305054)
			(end -0.12065 -0.305054)
			(stroke
				(width 0.1)
				(type default)
			)
			(layer "F.Fab")
		)
		(pad "1" smd circle
			(at -0.40005 0 180)
			(size 0 0)
			(layers "F.Cu" "F.Mask" "F.Paste")
			(net "P3V3_AUX")
		)
		(pad "2" smd circle
			(at 0.40005 0 180)
			(size 0 0)
			(layers "F.Cu" "F.Mask" "F.Paste")
			(net "GPU_HMC_PRSNT_N")
		)
	)
	(footprint ""
		(layer "F.Cu")
		(at 251.35967 -44.971462 -90)
		(property "Reference" "PC2211"
			(at 0 0 270)
			(layer "F.SilkS")
			(hide yes)
			(effects
				(font
					(size 1.27 1.27)
				)
			)
		)
		(property "Value" ""
			(at 0 0 270)
			(layer "F.Fab")
			(effects
				(font
					(size 1.27 1.27)
				)
			)
		)
		(duplicate_pad_numbers_are_jumpers no)
		(fp_line
			(start -0.7874 0.4064)
			(end -0.7874 -0.4064)
			(stroke
				(width 0.1524)
				(type default)
			)
			(layer "F.SilkS")
		)
		(fp_line
			(start 0.7874 0.4064)
			(end -0.7874 0.4064)
			(stroke
				(width 0.1524)
				(type default)
			)
			(layer "F.SilkS")
		)
		(fp_line
			(start -0.7874 -0.4064)
			(end 0.7874 -0.4064)
			(stroke
				(width 0.1524)
				(type default)
			)
			(layer "F.SilkS")
		)
		(fp_line
			(start 0.7874 -0.4064)
			(end 0.7874 0.4064)
			(stroke
				(width 0.1524)
				(type default)
			)
			(layer "F.SilkS")
		)
		(fp_line
			(start -0.67945 0.3048)
			(end -0.67945 -0.305054)
			(stroke
				(width 0.1)
				(type default)
			)
			(layer "F.Fab")
		)
		(fp_line
			(start -0.12065 0.3048)
			(end -0.67945 0.3048)
			(stroke
				(width 0.1)
				(type default)
			)
			(layer "F.Fab")
		)
		(fp_line
			(start 0.120396 0.3048)
			(end 0.120396 0.2794)
			(stroke
				(width 0.1)
				(type default)
			)
			(layer "F.Fab")
		)
		(fp_line
			(start 0.67945 0.3048)
			(end 0.120396 0.3048)
			(stroke
				(width 0.1)
				(type default)
			)
			(layer "F.Fab")
		)
		(fp_line
			(start -0.12065 0.2794)
			(end -0.12065 0.3048)
			(stroke
				(width 0.1)
				(type default)
			)
			(layer "F.Fab")
		)
		(fp_line
			(start 0.120396 0.2794)
			(end -0.12065 0.2794)
			(stroke
				(width 0.1)
				(type default)
			)
			(layer "F.Fab")
		)
		(fp_line
			(start -0.12065 -0.2794)
			(end 0.12065 -0.2794)
			(stroke
				(width 0.1)
				(type default)
			)
			(layer "F.Fab")
		)
		(fp_line
			(start 0.12065 -0.2794)
			(end 0.12065 -0.3048)
			(stroke
				(width 0.1)
				(type default)
			)
			(layer "F.Fab")
		)
		(fp_line
			(start 0.12065 -0.3048)
			(end 0.67945 -0.3048)
			(stroke
				(width 0.1)
				(type default)
			)
			(layer "F.Fab")
		)
		(fp_line
			(start 0.67945 -0.3048)
			(end 0.67945 0.3048)
			(stroke
				(width 0.1)
				(type default)
			)
			(layer "F.Fab")
		)
		(fp_line
			(start -0.67945 -0.305054)
			(end -0.12065 -0.305054)
			(stroke
				(width 0.1)
				(type default)
			)
			(layer "F.Fab")
		)
		(fp_line
			(start -0.12065 -0.305054)
			(end -0.12065 -0.2794)
			(stroke
				(width 0.1)
				(type default)
			)
			(layer "F.Fab")
		)
		(pad "1" smd circle
			(at -0.40005 0 270)
			(size 0 0)
			(layers "F.Cu" "F.Mask" "F.Paste")
			(net "GND")
		)
		(pad "2" smd circle
			(at 0.40005 0 270)
			(size 0 0)
			(layers "F.Cu" "F.Mask" "F.Paste")
			(net "P12V_E1S_REG_0")
		)
	)
)
